(kicad_pcb
	(version 20260206)
	(generator "pcbnew")
	(generator_version "10.0")
	(general
		(thickness 1.6)
		(legacy_teardrops no)
	)
	(paper "A4")
	(title_block
		(title "Bryce Canyon_SCC_16316-1_OCP.brd")
		(comment 1 "Bryce Canyon / footprints 1480-1487 of 1561")
	)
	(layers
		(0 "F.Cu" signal "TOP")
		(4 "In1.Cu" signal "L2GND")
		(6 "In2.Cu" signal "L3")
		(8 "In3.Cu" signal "L4VCC")
		(10 "In4.Cu" signal "L5VCC")
		(12 "In5.Cu" signal "L6")
		(14 "In6.Cu" signal "L7GND")
		(2 "B.Cu" signal "BOTTOM")
		(9 "F.Adhes" user "F.Adhesive")
		(11 "B.Adhes" user "B.Adhesive")
		(13 "F.Paste" user "Package Geometry/Pastemask Top")
		(15 "B.Paste" user "Package Geometry/Pastemask Bottom")
		(5 "F.SilkS" user "Ref Des/Silkscreen Top")
		(7 "B.SilkS" user "Ref Des/Silkscreen Bottom")
		(1 "F.Mask" user "Board Geometry/Soldermask Top")
		(3 "B.Mask" user "Board Geometry/Soldermask Bottom")
		(17 "Dwgs.User" user "User.Drawings")
		(19 "Cmts.User" user "User.Comments")
		(21 "Eco1.User" user "User.Eco1")
		(23 "Eco2.User" user "User.Eco2")
		(25 "Edge.Cuts" user "Board Geometry/Outline")
		(27 "Margin" user)
		(31 "F.CrtYd" user "Package Geometry/Place Bound Top")
		(29 "B.CrtYd" user "Package Geometry/Place Bound Bottom")
		(35 "F.Fab" user "Ref Des/Assembly Top")
		(33 "B.Fab" user "Ref Des/Assembly Bottom")
	)
	(footprint ""
		(layer "B.Cu")
		(at 184.465468 -36.87191 90)
		(property "Reference" "C491"
			(at 0 0 90)
			(layer "B.SilkS")
			(hide yes)
			(effects
				(font
					(size 1.27 1.27)
				)
				(justify mirror)
			)
		)
		(property "Value" "SCD1U6D3V1KX-GP"
			(at 2.8321 -1.7399 90)
			(unlocked yes)
			(layer "B.Fab")
			(hide yes)
			(effects
				(font
					(size 1.016 1.016)
					(thickness 0.1524)
				)
				(justify mirror)
			)
		)
		(property "Device Type" "C0201H13"
			(at 2.8321 -3.2639 90)
			(unlocked yes)
			(layer "B.Fab")
			(hide yes)
			(effects
				(font
					(size 1.016 1.016)
					(thickness 0.1524)
				)
				(justify mirror)
			)
		)
		(duplicate_pad_numbers_are_jumpers no)
		(fp_rect
			(start 0.2794 0.6477)
			(end -0.2794 -0.6477)
			(stroke
				(width 0)
				(type default)
			)
			(fill no)
			(layer "B.CrtYd")
		)
		(fp_rect
			(start 0.2794 0.6477)
			(end -0.2794 -0.6477)
			(stroke
				(width 0)
				(type default)
			)
			(fill no)
			(layer "B.Fab")
		)
		(pad "1" smd custom
			(at 0 -0.2794 270)
			(size 0.0762 0.0762)
			(layers "B.Cu" "B.Mask" "B.Paste")
			(net "P1V8_C")
			(options
				(clearance outline)
				(anchor circle)
			)
			(primitives
				(gr_poly
					(pts
						(arc
							(start 0.1524 0.127)
							(mid 0.137521 0.162921)
							(end 0.1016 0.1778)
						)
						(arc
							(start -0.1016 0.1778)
							(mid -0.137521 0.162921)
							(end -0.1524 0.127)
						)
						(arc
							(start -0.1524 -0.127)
							(mid -0.137521 -0.162921)
							(end -0.1016 -0.1778)
						)
						(arc
							(start 0.1016 -0.1778)
							(mid 0.137521 -0.162921)
							(end 0.1524 -0.127)
						)
					)
					(width 0)
					(fill yes)
				)
			)
		)
		(pad "2" smd custom
			(at 0 0.2794 270)
			(size 0.0762 0.0762)
			(layers "B.Cu" "B.Mask" "B.Paste")
			(net "GND")
			(options
				(clearance outline)
				(anchor circle)
			)
			(primitives
				(gr_poly
					(pts
						(arc
							(start 0.1524 0.127)
							(mid 0.137521 0.162921)
							(end 0.1016 0.1778)
						)
						(arc
							(start -0.1016 0.1778)
							(mid -0.137521 0.162921)
							(end -0.1524 0.127)
						)
						(arc
							(start -0.1524 -0.127)
							(mid -0.137521 -0.162921)
							(end -0.1016 -0.1778)
						)
						(arc
							(start 0.1016 -0.1778)
							(mid 0.137521 -0.162921)
							(end 0.1524 -0.127)
						)
					)
					(width 0)
					(fill yes)
				)
			)
		)
	)
	(footprint ""
		(layer "B.Cu")
		(at 174.1932 -120.488964 90)
		(property "Reference" "C706"
			(at 0 0 90)
			(layer "B.SilkS")
			(hide yes)
			(effects
				(font
					(size 1.27 1.27)
				)
				(justify mirror)
			)
		)
		(property "Value" "SC10U6D3V5KX-4GP"
			(at 0.0762 -6.1214 90)
			(unlocked yes)
			(layer "B.Fab")
			(hide yes)
			(effects
				(font
					(size 1.016 1.016)
					(thickness 0.1524)
				)
				(justify mirror)
			)
		)
		(property "Device Type" "C805H58"
			(at 0.0762 -8.1534 90)
			(unlocked yes)
			(layer "B.Fab")
			(hide yes)
			(effects
				(font
					(size 1.016 1.016)
					(thickness 0.1524)
				)
				(justify mirror)
			)
		)
		(duplicate_pad_numbers_are_jumpers no)
		(fp_line
			(start -0.635 0)
			(end 0.635 0)
			(stroke
				(width 0.508)
				(type default)
			)
			(layer "B.SilkS")
		)
		(fp_rect
			(start 0.9652 1.778)
			(end -0.9652 -1.778)
			(stroke
				(width 0)
				(type default)
			)
			(fill no)
			(layer "B.CrtYd")
		)
		(fp_poly
			(pts
				(xy 0.9652 -1.778) (xy -0.9652 -1.778) (xy -0.9652 1.778) (xy 0.9652 1.778)
			)
			(stroke
				(width 0)
				(type default)
			)
			(fill no)
			(layer "B.Fab")
		)
		(pad "1" smd rect
			(at 0 -0.9652 270)
			(size 1.397 1.143)
			(layers "B.Cu" "B.Mask" "B.Paste")
			(net "P3V3")
		)
		(pad "2" smd rect
			(at 0 0.9652 270)
			(size 1.397 1.143)
			(layers "B.Cu" "B.Mask" "B.Paste")
			(net "GND")
		)
	)
	(footprint ""
		(layer "B.Cu")
		(at 173.045882 -20.886166)
		(property "Reference" "C319"
			(at 0 0 0)
			(layer "B.SilkS")
			(hide yes)
			(effects
				(font
					(size 1.27 1.27)
				)
				(justify mirror)
			)
		)
		(property "Value" "SCD22U10V1KX-GP"
			(at 2.8321 -1.7399 0)
			(unlocked yes)
			(layer "B.Fab")
			(hide yes)
			(effects
				(font
					(size 1.016 1.016)
					(thickness 0.1524)
				)
				(justify mirror)
			)
		)
		(property "Device Type" "C0201H13"
			(at 2.8321 -3.2639 0)
			(unlocked yes)
			(layer "B.Fab")
			(hide yes)
			(effects
				(font
					(size 1.016 1.016)
					(thickness 0.1524)
				)
				(justify mirror)
			)
		)
		(duplicate_pad_numbers_are_jumpers no)
		(fp_rect
			(start 0.2794 0.6477)
			(end -0.2794 -0.6477)
			(stroke
				(width 0)
				(type default)
			)
			(fill no)
			(layer "B.CrtYd")
		)
		(fp_rect
			(start 0.2794 0.6477)
			(end -0.2794 -0.6477)
			(stroke
				(width 0)
				(type default)
			)
			(fill no)
			(layer "B.Fab")
		)
		(pad "1" smd custom
			(at 0 -0.2794 180)
			(size 0.0762 0.0762)
			(layers "B.Cu" "B.Mask" "B.Paste")
			(net "PCIE_SCC_TO_COMP_C_4_DP")
			(options
				(clearance outline)
				(anchor circle)
			)
			(primitives
				(gr_poly
					(pts
						(arc
							(start 0.1524 0.127)
							(mid 0.137521 0.162921)
							(end 0.1016 0.1778)
						)
						(arc
							(start -0.1016 0.1778)
							(mid -0.137521 0.162921)
							(end -0.1524 0.127)
						)
						(arc
							(start -0.1524 -0.127)
							(mid -0.137521 -0.162921)
							(end -0.1016 -0.1778)
						)
						(arc
							(start 0.1016 -0.1778)
							(mid 0.137521 -0.162921)
							(end 0.1524 -0.127)
						)
					)
					(width 0)
					(fill yes)
				)
			)
		)
		(pad "2" smd custom
			(at 0 0.2794 180)
			(size 0.0762 0.0762)
			(layers "B.Cu" "B.Mask" "B.Paste")
			(net "PCIE_SCC_TO_COMP_4_DP")
			(options
				(clearance outline)
				(anchor circle)
			)
			(primitives
				(gr_poly
					(pts
						(arc
							(start 0.1524 0.127)
							(mid 0.137521 0.162921)
							(end 0.1016 0.1778)
						)
						(arc
							(start -0.1016 0.1778)
							(mid -0.137521 0.162921)
							(end -0.1524 0.127)
						)
						(arc
							(start -0.1524 -0.127)
							(mid -0.137521 -0.162921)
							(end -0.1016 -0.1778)
						)
						(arc
							(start 0.1016 -0.1778)
							(mid 0.137521 -0.162921)
							(end 0.1524 -0.127)
						)
					)
					(width 0)
					(fill yes)
				)
			)
		)
	)
	(footprint ""
		(layer "B.Cu")
		(at 134.523988 -87.260684)
		(property "Reference" "R70"
			(at 0 0 0)
			(layer "B.SilkS")
			(hide yes)
			(effects
				(font
					(size 1.27 1.27)
				)
				(justify mirror)
			)
		)
		(property "Value" "1KR2F-3-GP"
			(at -0.064008 -3.993896 0)
			(unlocked yes)
			(layer "B.Fab")
			(hide yes)
			(effects
				(font
					(size 1.016 1.016)
					(thickness 0.1524)
				)
				(justify mirror)
			)
		)
		(property "Device Type" "R402H16"
			(at -0.064008 -5.517896 0)
			(unlocked yes)
			(layer "B.Fab")
			(hide yes)
			(effects
				(font
					(size 1.016 1.016)
					(thickness 0.1524)
				)
				(justify mirror)
			)
		)
		(duplicate_pad_numbers_are_jumpers no)
		(fp_line
			(start -0.508 -0.9398)
			(end 0.508 -0.9398)
			(stroke
				(width 0.1524)
				(type default)
			)
			(layer "B.SilkS")
		)
		(fp_line
			(start 0.508 -0.9398)
			(end 0.508 0.9398)
			(stroke
				(width 0.1524)
				(type default)
			)
			(layer "B.SilkS")
		)
		(fp_rect
			(start 0.508 0.9398)
			(end -0.508 -0.9398)
			(stroke
				(width 0)
				(type default)
			)
			(fill no)
			(layer "B.CrtYd")
		)
		(fp_rect
			(start 0.508 0.9398)
			(end -0.508 -0.9398)
			(stroke
				(width 0)
				(type default)
			)
			(fill no)
			(layer "B.Fab")
		)
		(pad "1" smd custom
			(at 0 -0.4445 180)
			(size 0.1397 0.1397)
			(layers "B.Cu" "B.Mask" "B.Paste")
			(net "P1V8_E")
			(options
				(clearance outline)
				(anchor circle)
			)
			(primitives
				(gr_poly
					(pts
						(arc
							(start -0.1778 0.2794)
							(mid -0.249642 0.249642)
							(end -0.2794 0.1778)
						)
						(arc
							(start -0.2794 -0.1778)
							(mid -0.249642 -0.249642)
							(end -0.1778 -0.2794)
						)
						(arc
							(start 0.1778 -0.2794)
							(mid 0.249642 -0.249642)
							(end 0.2794 -0.1778)
						)
						(arc
							(start 0.2794 0.1778)
							(mid 0.249642 0.249642)
							(end 0.1778 0.2794)
						)
					)
					(width 0)
					(fill yes)
				)
			)
		)
		(pad "2" smd custom
			(at 0 0.4445 180)
			(size 0.1397 0.1397)
			(layers "B.Cu" "B.Mask" "B.Paste")
			(net "EXP_I2C_SCL11")
			(options
				(clearance outline)
				(anchor circle)
			)
			(primitives
				(gr_poly
					(pts
						(arc
							(start -0.1778 0.2794)
							(mid -0.249642 0.249642)
							(end -0.2794 0.1778)
						)
						(arc
							(start -0.2794 -0.1778)
							(mid -0.249642 -0.249642)
							(end -0.1778 -0.2794)
						)
						(arc
							(start 0.1778 -0.2794)
							(mid 0.249642 -0.249642)
							(end 0.2794 -0.1778)
						)
						(arc
							(start 0.2794 0.1778)
							(mid 0.249642 0.249642)
							(end 0.1778 0.2794)
						)
					)
					(width 0)
					(fill yes)
				)
			)
		)
	)
	(footprint ""
		(layer "B.Cu")
		(at 179.451 -31.75 -90)
		(property "Reference" "C470"
			(at 0 0 90)
			(layer "B.SilkS")
			(hide yes)
			(effects
				(font
					(size 1.27 1.27)
				)
				(justify mirror)
			)
		)
		(property "Value" "SCD1U6D3V1KX-GP"
			(at 2.8321 -1.7399 270)
			(unlocked yes)
			(layer "B.Fab")
			(hide yes)
			(effects
				(font
					(size 1.016 1.016)
					(thickness 0.1524)
				)
				(justify mirror)
			)
		)
		(property "Device Type" "C0201H13"
			(at 2.8321 -3.2639 270)
			(unlocked yes)
			(layer "B.Fab")
			(hide yes)
			(effects
				(font
					(size 1.016 1.016)
					(thickness 0.1524)
				)
				(justify mirror)
			)
		)
		(duplicate_pad_numbers_are_jumpers no)
		(fp_rect
			(start 0.2794 0.6477)
			(end -0.2794 -0.6477)
			(stroke
				(width 0)
				(type default)
			)
			(fill no)
			(layer "B.CrtYd")
		)
		(fp_rect
			(start 0.2794 0.6477)
			(end -0.2794 -0.6477)
			(stroke
				(width 0)
				(type default)
			)
			(fill no)
			(layer "B.Fab")
		)
		(pad "1" smd custom
			(at 0 -0.2794 90)
			(size 0.0762 0.0762)
			(layers "B.Cu" "B.Mask" "B.Paste")
			(net "P1V8_C")
			(options
				(clearance outline)
				(anchor circle)
			)
			(primitives
				(gr_poly
					(pts
						(arc
							(start 0.1524 0.127)
							(mid 0.137521 0.162921)
							(end 0.1016 0.1778)
						)
						(arc
							(start -0.1016 0.1778)
							(mid -0.137521 0.162921)
							(end -0.1524 0.127)
						)
						(arc
							(start -0.1524 -0.127)
							(mid -0.137521 -0.162921)
							(end -0.1016 -0.1778)
						)
						(arc
							(start 0.1016 -0.1778)
							(mid 0.137521 -0.162921)
							(end 0.1524 -0.127)
						)
					)
					(width 0)
					(fill yes)
				)
			)
		)
		(pad "2" smd custom
			(at 0 0.2794 90)
			(size 0.0762 0.0762)
			(layers "B.Cu" "B.Mask" "B.Paste")
			(net "GND")
			(options
				(clearance outline)
				(anchor circle)
			)
			(primitives
				(gr_poly
					(pts
						(arc
							(start 0.1524 0.127)
							(mid 0.137521 0.162921)
							(end 0.1016 0.1778)
						)
						(arc
							(start -0.1016 0.1778)
							(mid -0.137521 0.162921)
							(end -0.1524 0.127)
						)
						(arc
							(start -0.1524 -0.127)
							(mid -0.137521 -0.162921)
							(end -0.1016 -0.1778)
						)
						(arc
							(start 0.1016 -0.1778)
							(mid 0.137521 -0.162921)
							(end 0.1524 -0.127)
						)
					)
					(width 0)
					(fill yes)
				)
			)
		)
	)
	(footprint ""
		(layer "B.Cu")
		(at 110.5408 -84.4042 180)
		(property "Reference" "R137"
			(at 0 0 0)
			(layer "B.SilkS")
			(hide yes)
			(effects
				(font
					(size 1.27 1.27)
				)
				(justify mirror)
			)
		)
		(property "Value" "4K75R2F-1-GP"
			(at -0.064008 -3.993896 180)
			(unlocked yes)
			(layer "B.Fab")
			(hide yes)
			(effects
				(font
					(size 1.016 1.016)
					(thickness 0.1524)
				)
				(justify mirror)
			)
		)
		(property "Device Type" "R402H16"
			(at -0.064008 -5.517896 180)
			(unlocked yes)
			(layer "B.Fab")
			(hide yes)
			(effects
				(font
					(size 1.016 1.016)
					(thickness 0.1524)
				)
				(justify mirror)
			)
		)
		(duplicate_pad_numbers_are_jumpers no)
		(fp_line
			(start 0.508 -0.9398)
			(end 0.508 0.9398)
			(stroke
				(width 0.1524)
				(type default)
			)
			(layer "B.SilkS")
		)
		(fp_line
			(start -0.508 -0.9398)
			(end 0.508 -0.9398)
			(stroke
				(width 0.1524)
				(type default)
			)
			(layer "B.SilkS")
		)
		(fp_rect
			(start 0.508 0.9398)
			(end -0.508 -0.9398)
			(stroke
				(width 0)
				(type default)
			)
			(fill no)
			(layer "B.CrtYd")
		)
		(fp_rect
			(start 0.508 0.9398)
			(end -0.508 -0.9398)
			(stroke
				(width 0)
				(type default)
			)
			(fill no)
			(layer "B.Fab")
		)
		(pad "1" smd custom
			(at 0 -0.4445)
			(size 0.1397 0.1397)
			(layers "B.Cu" "B.Mask" "B.Paste")
			(net "EXP_XM_WE_N")
			(options
				(clearance outline)
				(anchor circle)
			)
			(primitives
				(gr_poly
					(pts
						(arc
							(start -0.1778 0.2794)
							(mid -0.249642 0.249642)
							(end -0.2794 0.1778)
						)
						(arc
							(start -0.2794 -0.1778)
							(mid -0.249642 -0.249642)
							(end -0.1778 -0.2794)
						)
						(arc
							(start 0.1778 -0.2794)
							(mid 0.249642 -0.249642)
							(end 0.2794 -0.1778)
						)
						(arc
							(start 0.2794 0.1778)
							(mid 0.249642 0.249642)
							(end 0.1778 0.2794)
						)
					)
					(width 0)
					(fill yes)
				)
			)
		)
		(pad "2" smd custom
			(at 0 0.4445)
			(size 0.1397 0.1397)
			(layers "B.Cu" "B.Mask" "B.Paste")
			(net "P1V8_E")
			(options
				(clearance outline)
				(anchor circle)
			)
			(primitives
				(gr_poly
					(pts
						(arc
							(start -0.1778 0.2794)
							(mid -0.249642 0.249642)
							(end -0.2794 0.1778)
						)
						(arc
							(start -0.2794 -0.1778)
							(mid -0.249642 -0.249642)
							(end -0.1778 -0.2794)
						)
						(arc
							(start 0.1778 -0.2794)
							(mid 0.249642 -0.249642)
							(end 0.2794 -0.1778)
						)
						(arc
							(start 0.2794 0.1778)
							(mid 0.249642 0.249642)
							(end 0.1778 0.2794)
						)
					)
					(width 0)
					(fill yes)
				)
			)
		)
	)
	(footprint ""
		(layer "B.Cu")
		(at 124.515118 -59.488832 90)
		(property "Reference" "C286"
			(at 0 0 90)
			(layer "B.SilkS")
			(hide yes)
			(effects
				(font
					(size 1.27 1.27)
				)
				(justify mirror)
			)
		)
		(property "Value" "SCD1U6D3V1KX-GP"
			(at 2.8321 -1.7399 90)
			(unlocked yes)
			(layer "B.Fab")
			(hide yes)
			(effects
				(font
					(size 1.016 1.016)
					(thickness 0.1524)
				)
				(justify mirror)
			)
		)
		(property "Device Type" "C0201H13"
			(at 2.8321 -3.2639 90)
			(unlocked yes)
			(layer "B.Fab")
			(hide yes)
			(effects
				(font
					(size 1.016 1.016)
					(thickness 0.1524)
				)
				(justify mirror)
			)
		)
		(duplicate_pad_numbers_are_jumpers no)
		(fp_rect
			(start 0.2794 0.6477)
			(end -0.2794 -0.6477)
			(stroke
				(width 0)
				(type default)
			)
			(fill no)
			(layer "B.CrtYd")
		)
		(fp_rect
			(start 0.2794 0.6477)
			(end -0.2794 -0.6477)
			(stroke
				(width 0)
				(type default)
			)
			(fill no)
			(layer "B.Fab")
		)
		(pad "1" smd custom
			(at 0 -0.2794 270)
			(size 0.0762 0.0762)
			(layers "B.Cu" "B.Mask" "B.Paste")
			(net "GB_VDDA")
			(options
				(clearance outline)
				(anchor circle)
			)
			(primitives
				(gr_poly
					(pts
						(arc
							(start 0.1524 0.127)
							(mid 0.137521 0.162921)
							(end 0.1016 0.1778)
						)
						(arc
							(start -0.1016 0.1778)
							(mid -0.137521 0.162921)
							(end -0.1524 0.127)
						)
						(arc
							(start -0.1524 -0.127)
							(mid -0.137521 -0.162921)
							(end -0.1016 -0.1778)
						)
						(arc
							(start 0.1016 -0.1778)
							(mid 0.137521 -0.162921)
							(end 0.1524 -0.127)
						)
					)
					(width 0)
					(fill yes)
				)
			)
		)
		(pad "2" smd custom
			(at 0 0.2794 270)
			(size 0.0762 0.0762)
			(layers "B.Cu" "B.Mask" "B.Paste")
			(net "GND")
			(options
				(clearance outline)
				(anchor circle)
			)
			(primitives
				(gr_poly
					(pts
						(arc
							(start 0.1524 0.127)
							(mid 0.137521 0.162921)
							(end 0.1016 0.1778)
						)
						(arc
							(start -0.1016 0.1778)
							(mid -0.137521 0.162921)
							(end -0.1524 0.127)
						)
						(arc
							(start -0.1524 -0.127)
							(mid -0.137521 -0.162921)
							(end -0.1016 -0.1778)
						)
						(arc
							(start 0.1016 -0.1778)
							(mid 0.137521 -0.162921)
							(end 0.1524 -0.127)
						)
					)
					(width 0)
					(fill yes)
				)
			)
		)
	)
	(footprint ""
		(layer "B.Cu")
		(at 135.66648 -61.304678 180)
		(property "Reference" "C23"
			(at 0 0 0)
			(layer "B.SilkS")
			(hide yes)
			(effects
				(font
					(size 1.27 1.27)
				)
				(justify mirror)
			)
		)
		(property "Value" "SCD01U16V1KX-GP"
			(at 2.8321 -1.7399 180)
			(unlocked yes)
			(layer "B.Fab")
			(hide yes)
			(effects
				(font
					(size 1.016 1.016)
					(thickness 0.1524)
				)
				(justify mirror)
			)
		)
		(property "Device Type" "C0201H13"
			(at 2.8321 -3.2639 180)
			(unlocked yes)
			(layer "B.Fab")
			(hide yes)
			(effects
				(font
					(size 1.016 1.016)
					(thickness 0.1524)
				)
				(justify mirror)
			)
		)
		(duplicate_pad_numbers_are_jumpers no)
		(fp_rect
			(start 0.2794 0.6477)
			(end -0.2794 -0.6477)
			(stroke
				(width 0)
				(type default)
			)
			(fill no)
			(layer "B.CrtYd")
		)
		(fp_rect
			(start 0.2794 0.6477)
			(end -0.2794 -0.6477)
			(stroke
				(width 0)
				(type default)
			)
			(fill no)
			(layer "B.Fab")
		)
		(pad "1" smd custom
			(at 0 -0.2794)
			(size 0.0762 0.0762)
			(layers "B.Cu" "B.Mask" "B.Paste")
			(net "PHY_DPB_TO_SCC_0_DP")
			(options
				(clearance outline)
				(anchor circle)
			)
			(primitives
				(gr_poly
					(pts
						(arc
							(start 0.1524 0.127)
							(mid 0.137521 0.162921)
							(end 0.1016 0.1778)
						)
						(arc
							(start -0.1016 0.1778)
							(mid -0.137521 0.162921)
							(end -0.1524 0.127)
						)
						(arc
							(start -0.1524 -0.127)
							(mid -0.137521 -0.162921)
							(end -0.1016 -0.1778)
						)
						(arc
							(start 0.1016 -0.1778)
							(mid 0.137521 -0.162921)
							(end 0.1524 -0.127)
						)
					)
					(width 0)
					(fill yes)
				)
			)
		)
		(pad "2" smd custom
			(at 0 0.2794)
			(size 0.0762 0.0762)
			(layers "B.Cu" "B.Mask" "B.Paste")
			(net "PHY_DPB_TO_SCC_C_0_DP")
			(options
				(clearance outline)
				(anchor circle)
			)
			(primitives
				(gr_poly
					(pts
						(arc
							(start 0.1524 0.127)
							(mid 0.137521 0.162921)
							(end 0.1016 0.1778)
						)
						(arc
							(start -0.1016 0.1778)
							(mid -0.137521 0.162921)
							(end -0.1524 0.127)
						)
						(arc
							(start -0.1524 -0.127)
							(mid -0.137521 -0.162921)
							(end -0.1016 -0.1778)
						)
						(arc
							(start 0.1016 -0.1778)
							(mid 0.137521 -0.162921)
							(end 0.1524 -0.127)
						)
					)
					(width 0)
					(fill yes)
				)
			)
		)
	)
)
